# T6G (Grand Teton) — schematic netlist excerpt (pin names and nets, part order shuffled) for the footprints in the layout excerpt that follows; sources: Cadence DE-HDL packaged netlist, KiCad conversion of 04192023_DAF0TMB3IC0_F0TG_MB_C_brd_V02_OCP.brd

PU45  ISL99390FRZTR5935  ISL99390FRZ-TR5935 IC  pkg QFN21_6X5XB  page 225
  VOS  = PVDD11_S3_P1_VOS2
  AGND  = GND
  VCC  = PVDD11_S3_P1_VCC2
  PVCC  = PVDD11_S3_P1_PVCC
  PGND1  = GND
  GL1  = NC_PVDD11_S3_P1_GL1_2
  PGND2  = GND
  SW  = SW_PVDD11_S3_P1_SW2
  VIN1  = SW_P12V_AUX_PVDD11_S3_P1_FLT
  VIN2  = SW_P12V_AUX_PVDD11_S3_P1_FLT
  DNC  = NC_PVDD11_S3_P1_DNC2
  PHASE  = SW_PVDD11_S3_P1_PH2
  BOOT  = SW_PVDD11_S3_P1_BOOT2
  PWM  = PVDD11_S3_P1_PWM2
  EN  = PVDD11_S3_P1_VCC2
  TOUT_FLT  = PVDD11_S3_P1_TEMP0
  LSET  = PVDD11_S3_P1_LSET2
  IOUT  = PVDD11_S3_P1_IMON2
  REFIN  = PVDD11_S3_P1_VCCS
  PGND3  = GND
  GL2  = NC_PVDD11_S3_P1_GL2_2

(kicad_pcb
	(version 20260206)
	(generator "pcbnew")
	(generator_version "10.0")
	(general
		(thickness 1.6)
		(legacy_teardrops no)
	)
	(paper "A4")
	(title_block
		(title "04192023_DAF0TMB3IC0_F0TG_MB_C_brd_V02_OCP.brd")
		(comment 1 "Grand Teton / footprints 607-607 of 8354")
	)
	(layers
		(0 "F.Cu" signal "TOP")
		(4 "In1.Cu" signal "GND")
		(6 "In2.Cu" signal "IN1")
		(8 "In3.Cu" signal "GND1")
		(10 "In4.Cu" signal "IN2")
		(12 "In5.Cu" signal "GND2")
		(14 "In6.Cu" signal "IN3")
		(16 "In7.Cu" signal "GND3")
		(18 "In8.Cu" signal "VCC")
		(20 "In9.Cu" signal "VCC1")
		(22 "In10.Cu" signal "GND4")
		(24 "In11.Cu" signal "IN4")
		(26 "In12.Cu" signal "GND5")
		(28 "In13.Cu" signal "IN5")
		(30 "In14.Cu" signal "GND6")
		(32 "In15.Cu" signal "IN6")
		(34 "In16.Cu" signal "GND7")
		(2 "B.Cu" signal "BOTTOM")
		(9 "F.Adhes" user "F.Adhesive")
		(11 "B.Adhes" user "B.Adhesive")
		(13 "F.Paste" user "Package Geometry/Pastemask Top")
		(15 "B.Paste" user "Package Geometry/Pastemask Bottom")
		(5 "F.SilkS" user "Ref Des/Silkscreen Top")
		(7 "B.SilkS" user "Ref Des/Silkscreen Bottom")
		(1 "F.Mask" user "Board Geometry/Soldermask Top")
		(3 "B.Mask" user "Board Geometry/Soldermask Bottom")
		(17 "Dwgs.User" user "User.Drawings")
		(19 "Cmts.User" user "User.Comments")
		(21 "Eco1.User" user "User.Eco1")
		(23 "Eco2.User" user "User.Eco2")
		(25 "Edge.Cuts" user "Board Geometry/Outline")
		(27 "Margin" user)
		(31 "F.CrtYd" user "Package Geometry/Place Bound Top")
		(29 "B.CrtYd" user "Package Geometry/Place Bound Bottom")
		(35 "F.Fab" user "Ref Des/Assembly Top")
		(33 "B.Fab" user "Ref Des/Assembly Bottom")
	)
	(footprint ""
		(layer "F.Cu")
		(at 191.246506 -351.320862)
		(property "Reference" "PU45"
			(at -3.032506 -7.935468 0)
			(unlocked yes)
			(layer "F.SilkS")
			(effects
				(font
					(size 0.7874 0.5842)
					(thickness 0.1524)
				)
				(justify left)
			)
		)
		(property "Value" ""
			(at 0 0 0)
			(layer "F.Fab")
			(effects
				(font
					(size 1.27 1.27)
				)
			)
		)
		(duplicate_pad_numbers_are_jumpers no)
		(fp_line
			(start -2.500122 -2.999994)
			(end -2.24409 -2.999994)
			(stroke
				(width 0.1524)
				(type default)
			)
			(layer "F.SilkS")
		)
		(fp_line
			(start -2.500122 -2.529078)
			(end -2.500122 -2.999994)
			(stroke
				(width 0.1524)
				(type default)
			)
			(layer "F.SilkS")
		)
		(fp_line
			(start -2.500122 0.6604)
			(end -2.500122 0.229108)
			(stroke
				(width 0.1524)
				(type default)
			)
			(layer "F.SilkS")
		)
		(fp_line
			(start -2.500122 2.999994)
			(end -2.500122 2.339594)
			(stroke
				(width 0.1524)
				(type default)
			)
			(layer "F.SilkS")
		)
		(fp_line
			(start -2.2987 2.999994)
			(end -2.500122 2.999994)
			(stroke
				(width 0.1524)
				(type default)
			)
			(layer "F.SilkS")
		)
		(fp_line
			(start 2.31394 -2.999994)
			(end 2.500122 -2.999994)
			(stroke
				(width 0.1524)
				(type default)
			)
			(layer "F.SilkS")
		)
		(fp_line
			(start 2.500122 -2.999994)
			(end 2.500122 -2.44348)
			(stroke
				(width 0.1524)
				(type default)
			)
			(layer "F.SilkS")
		)
		(fp_line
			(start 2.500122 2.339594)
			(end 2.500122 2.999994)
			(stroke
				(width 0.1524)
				(type default)
			)
			(layer "F.SilkS")
		)
		(fp_line
			(start 2.500122 2.999994)
			(end 2.2987 2.999994)
			(stroke
				(width 0.1524)
				(type default)
			)
			(layer "F.SilkS")
		)
		(fp_poly
			(pts
				(xy -2.768854 -2.421382) (xy -3.442462 -2.645918) (xy -2.99339 -3.09499)
			)
			(stroke
				(width 0)
				(type default)
			)
			(fill yes)
			(layer "F.SilkS")
		)
		(fp_line
			(start -2.500122 -2.999994)
			(end 2.500122 -2.999994)
			(stroke
				(width 0.1)
				(type default)
			)
			(layer "F.Fab")
		)
		(fp_line
			(start -2.500122 2.999994)
			(end -2.500122 -2.999994)
			(stroke
				(width 0.1)
				(type default)
			)
			(layer "F.Fab")
		)
		(fp_line
			(start 2.500122 -2.999994)
			(end 2.500122 2.999994)
			(stroke
				(width 0.1)
				(type default)
			)
			(layer "F.Fab")
		)
		(fp_line
			(start 2.500122 2.999994)
			(end -2.500122 2.999994)
			(stroke
				(width 0.1)
				(type default)
			)
			(layer "F.Fab")
		)
		(fp_poly
			(pts
				(xy -4.218432 -2.783078) (xy -4.218432 -1.767078) (xy -3.202432 -2.275078)
			)
			(stroke
				(width 0)
				(type default)
			)
			(fill yes)
			(layer "F.Fab")
		)
		(pad "1" smd rect
			(at -2.400046 -2.275078 90)
			(size 0.2286 0.6096)
			(layers "F.Cu" "F.Mask" "F.Paste")
			(net "PVDD11_S3_P1_VOS2")
		)
		(pad "2" smd rect
			(at -2.400046 -1.82499 90)
			(size 0.2286 0.6096)
			(layers "F.Cu" "F.Mask" "F.Paste")
			(net "GND")
		)
		(pad "3" smd rect
			(at -2.400046 -1.374902 90)
			(size 0.2286 0.6096)
			(layers "F.Cu" "F.Mask" "F.Paste")
			(net "PVDD11_S3_P1_VCC2")
		)
		(pad "4" smd rect
			(at -2.400046 -0.925068 90)
			(size 0.2286 0.6096)
			(layers "F.Cu" "F.Mask" "F.Paste")
			(net "PVDD11_S3_P1_PVCC")
		)
		(pad "5" smd rect
			(at -2.400046 -0.47498 90)
			(size 0.2286 0.6096)
			(layers "F.Cu" "F.Mask" "F.Paste")
			(net "GND")
		)
		(pad "6" smd rect
			(at -2.400046 -0.024892 90)
			(size 0.2286 0.6096)
			(layers "F.Cu" "F.Mask" "F.Paste")
			(net "NC_PVDD11_S3_P1_GL1_2")
		)
		(pad "7_9-20_24" smd circle
			(at 0 1.150112 90)
			(size 0 0)
			(layers "F.Cu" "F.Mask" "F.Paste")
			(net "GND")
		)
		(pad "10_19" smd rect
			(at 0 2.899918 90)
			(size 0.6096 4.318)
			(layers "F.Cu" "F.Mask" "F.Paste")
			(net "SW_PVDD11_S3_P1_SW2")
		)
		(pad "25_29" smd rect
			(at 1.549908 -1.279906 270)
			(size 2.0574 2.3114)
			(layers "F.Cu" "F.Mask" "F.Paste")
			(net "SW_P12V_AUX_PVDD11_S3_P1_FLT")
		)
		(pad "30" smd rect
			(at 2.05994 -2.899918)
			(size 0.2286 0.6096)
			(layers "F.Cu" "F.Mask" "F.Paste")
			(net "SW_P12V_AUX_PVDD11_S3_P1_FLT")
		)
		(pad "31" smd rect
			(at 1.610106 -2.899918)
			(size 0.2286 0.6096)
			(layers "F.Cu" "F.Mask" "F.Paste")
			(net "NC_PVDD11_S3_P1_DNC2")
		)
		(pad "32" smd rect
			(at 1.160018 -2.899918)
			(size 0.2286 0.6096)
			(layers "F.Cu" "F.Mask" "F.Paste")
			(net "SW_PVDD11_S3_P1_PH2")
		)
		(pad "33" smd rect
			(at 0.70993 -2.899918)
			(size 0.2286 0.6096)
			(layers "F.Cu" "F.Mask" "F.Paste")
			(net "SW_PVDD11_S3_P1_BOOT2")
		)
		(pad "34" smd rect
			(at 0.260096 -2.899918)
			(size 0.2286 0.6096)
			(layers "F.Cu" "F.Mask" "F.Paste")
			(net "PVDD11_S3_P1_PWM2")
		)
		(pad "35" smd rect
			(at -0.189992 -2.899918)
			(size 0.2286 0.6096)
			(layers "F.Cu" "F.Mask" "F.Paste")
			(net "PVDD11_S3_P1_VCC2")
		)
		(pad "36" smd rect
			(at -0.64008 -2.899918)
			(size 0.2286 0.6096)
			(layers "F.Cu" "F.Mask" "F.Paste")
			(net "PVDD11_S3_P1_TEMP0")
		)
		(pad "37" smd rect
			(at -1.089914 -2.899918)
			(size 0.2286 0.6096)
			(layers "F.Cu" "F.Mask" "F.Paste")
			(net "PVDD11_S3_P1_LSET2")
		)
		(pad "38" smd rect
			(at -1.540002 -2.899918)
			(size 0.2286 0.6096)
			(layers "F.Cu" "F.Mask" "F.Paste")
			(net "PVDD11_S3_P1_IMON2")
		)
		(pad "39" smd rect
			(at -1.99009 -2.899918)
			(size 0.2286 0.6096)
			(layers "F.Cu" "F.Mask" "F.Paste")
			(net "PVDD11_S3_P1_VCCS")
		)
		(pad "40" smd rect
			(at -0.87503 -1.27508)
			(size 1.7526 1.9558)
			(layers "F.Cu" "F.Mask" "F.Paste")
			(net "GND")
		)
		(pad "41" smd rect
			(at -1.525016 0.249936 270)
			(size 0.3048 0.4572)
			(layers "F.Cu" "F.Mask" "F.Paste")
			(net "NC_PVDD11_S3_P1_GL2_2")
		)
		(zone
			(layer "F.Cu")
			(hatch none 0.5)
			(connect_pads
				(clearance 0)
			)
			(min_thickness 0.25)
			(keepout
				(tracks not_allowed)
				(vias allowed)
				(pads allowed)
				(copperpour not_allowed)
				(footprints allowed)
			)
			(placement
				(enabled no)
				(sheetname "")
			)
			(fill
				(thermal_gap 0.5)
				(thermal_bridge_width 0.5)
				(island_removal_mode 0)
			)
			(polygon
				(pts
					(xy 188.746384 -348.774512) (xy 188.746384 -349.070168) (xy 193.746628 -349.070168) (xy 193.746628 -348.320868)
					(xy 193.456306 -348.320868) (xy 193.456306 -348.776544) (xy 189.036706 -348.776544) (xy 189.036706 -348.774512)
				)
			)
		)
		(zone
			(layer "F.Cu")
			(hatch none 0.5)
			(connect_pads
				(clearance 0)
			)
			(min_thickness 0.25)
			(keepout
				(tracks not_allowed)
				(vias allowed)
				(pads allowed)
				(copperpour not_allowed)
				(footprints allowed)
			)
			(placement
				(enabled no)
				(sheetname "")
			)
			(fill
				(thermal_gap 0.5)
				(thermal_bridge_width 0.5)
				(island_removal_mode 0)
			)
			(polygon
				(pts
					(xy 191.298576 -351.57664) (xy 191.298576 -353.624642) (xy 189.444376 -353.624642) (xy 189.444376 -353.383596)
					(xy 189.20206 -353.383596) (xy 189.20206 -353.86518) (xy 193.023744 -353.86518) (xy 193.023744 -353.680268)
					(xy 191.589914 -353.680268) (xy 191.589914 -351.521268) (xy 193.746628 -351.521268) (xy 193.746628 -351.271586)
					(xy 191.60363 -351.271586)
				)
			)
		)
	)
)
